(kicad_pcb
	(version 20260206)
	(generator "pcbnew")
	(generator_version "10.0")
	(general
		(thickness 1.6)
		(legacy_teardrops no)
	)
	(paper "A4")
	(title_block
		(title "12092022_DA0F0TFB6D0_F0T_FAN_BOARD_MP5048_D_brd_v02_OCP.brd")
		(comment 1 "Grand Teton / footprints 80-85 of 924")
	)
	(layers
		(0 "F.Cu" signal "TOP")
		(4 "In1.Cu" signal "GND")
		(6 "In2.Cu" signal "IN1")
		(8 "In3.Cu" signal "IN2")
		(10 "In4.Cu" signal "GND1")
		(2 "B.Cu" signal "BOTTOM")
		(9 "F.Adhes" user "F.Adhesive")
		(11 "B.Adhes" user "B.Adhesive")
		(13 "F.Paste" user "Package Geometry/Pastemask Top")
		(15 "B.Paste" user "Package Geometry/Pastemask Bottom")
		(5 "F.SilkS" user "Ref Des/Silkscreen Top")
		(7 "B.SilkS" user "Ref Des/Silkscreen Bottom")
		(1 "F.Mask" user "Board Geometry/Soldermask Top")
		(3 "B.Mask" user "Board Geometry/Soldermask Bottom")
		(17 "Dwgs.User" user "User.Drawings")
		(19 "Cmts.User" user "User.Comments")
		(21 "Eco1.User" user "User.Eco1")
		(23 "Eco2.User" user "User.Eco2")
		(25 "Edge.Cuts" user "Board Geometry/Outline")
		(27 "Margin" user)
		(31 "F.CrtYd" user "Package Geometry/Place Bound Top")
		(29 "B.CrtYd" user "Package Geometry/Place Bound Bottom")
		(35 "F.Fab" user "Ref Des/Assembly Top")
		(33 "B.Fab" user "Ref Des/Assembly Bottom")
	)
	(footprint ""
		(layer "F.Cu")
		(at 30.353 -182.372)
		(property "Reference" "R509"
			(at 0 0 0)
			(layer "F.SilkS")
			(hide yes)
			(effects
				(font
					(size 1.27 1.27)
				)
			)
		)
		(property "Value" ""
			(at 0 0 0)
			(layer "F.Fab")
			(effects
				(font
					(size 1.27 1.27)
				)
			)
		)
		(duplicate_pad_numbers_are_jumpers no)
		(fp_line
			(start -0.7874 -0.4064)
			(end 0.7874 -0.4064)
			(stroke
				(width 0.1524)
				(type default)
			)
			(layer "F.SilkS")
		)
		(fp_line
			(start -0.7874 0.4064)
			(end -0.7874 -0.4064)
			(stroke
				(width 0.1524)
				(type default)
			)
			(layer "F.SilkS")
		)
		(fp_line
			(start 0.7874 -0.4064)
			(end 0.7874 0.4064)
			(stroke
				(width 0.1524)
				(type default)
			)
			(layer "F.SilkS")
		)
		(fp_line
			(start 0.7874 0.4064)
			(end -0.7874 0.4064)
			(stroke
				(width 0.1524)
				(type default)
			)
			(layer "F.SilkS")
		)
		(fp_line
			(start -0.67945 -0.305054)
			(end -0.12065 -0.305054)
			(stroke
				(width 0.1)
				(type default)
			)
			(layer "F.Fab")
		)
		(fp_line
			(start -0.67945 0.3048)
			(end -0.67945 -0.305054)
			(stroke
				(width 0.1)
				(type default)
			)
			(layer "F.Fab")
		)
		(fp_line
			(start -0.12065 -0.305054)
			(end -0.12065 -0.2794)
			(stroke
				(width 0.1)
				(type default)
			)
			(layer "F.Fab")
		)
		(fp_line
			(start -0.12065 -0.2794)
			(end 0.12065 -0.2794)
			(stroke
				(width 0.1)
				(type default)
			)
			(layer "F.Fab")
		)
		(fp_line
			(start -0.12065 0.2794)
			(end -0.12065 0.3048)
			(stroke
				(width 0.1)
				(type default)
			)
			(layer "F.Fab")
		)
		(fp_line
			(start -0.12065 0.3048)
			(end -0.67945 0.3048)
			(stroke
				(width 0.1)
				(type default)
			)
			(layer "F.Fab")
		)
		(fp_line
			(start 0.120396 0.2794)
			(end -0.12065 0.2794)
			(stroke
				(width 0.1)
				(type default)
			)
			(layer "F.Fab")
		)
		(fp_line
			(start 0.120396 0.3048)
			(end 0.120396 0.2794)
			(stroke
				(width 0.1)
				(type default)
			)
			(layer "F.Fab")
		)
		(fp_line
			(start 0.12065 -0.3048)
			(end 0.67945 -0.3048)
			(stroke
				(width 0.1)
				(type default)
			)
			(layer "F.Fab")
		)
		(fp_line
			(start 0.12065 -0.2794)
			(end 0.12065 -0.3048)
			(stroke
				(width 0.1)
				(type default)
			)
			(layer "F.Fab")
		)
		(fp_line
			(start 0.67945 -0.3048)
			(end 0.67945 0.3048)
			(stroke
				(width 0.1)
				(type default)
			)
			(layer "F.Fab")
		)
		(fp_line
			(start 0.67945 0.3048)
			(end 0.120396 0.3048)
			(stroke
				(width 0.1)
				(type default)
			)
			(layer "F.Fab")
		)
		(pad "1" smd circle
			(at -0.40005 0)
			(size 0 0)
			(layers "F.Cu" "F.Mask" "F.Paste")
			(net "P3V3_AUX")
		)
		(pad "2" smd circle
			(at 0.40005 0)
			(size 0 0)
			(layers "F.Cu" "F.Mask" "F.Paste")
			(net "P52V_FAN_0_BUFF_EN")
		)
	)
	(footprint ""
		(layer "F.Cu")
		(at 36.322 -116.008912)
		(property "Reference" "D278"
			(at 2.23774 -0.669798 0)
			(unlocked yes)
			(layer "F.SilkS")
			(effects
				(font
					(size 0.7874 0.5842)
					(thickness 0.1524)
				)
				(justify left)
			)
		)
		(property "Value" ""
			(at 0 0 0)
			(layer "F.Fab")
			(effects
				(font
					(size 1.27 1.27)
				)
			)
		)
		(duplicate_pad_numbers_are_jumpers no)
		(fp_line
			(start -0.854964 -0.450088)
			(end -0.854964 0.450088)
			(stroke
				(width 0.1524)
				(type default)
			)
			(layer "F.SilkS")
		)
		(fp_line
			(start -0.854964 0.450088)
			(end 0.925068 0.450088)
			(stroke
				(width 0.1524)
				(type default)
			)
			(layer "F.SilkS")
		)
		(fp_line
			(start 0.845058 0.4064)
			(end 0.845058 -0.381)
			(stroke
				(width 0.1524)
				(type default)
			)
			(layer "F.SilkS")
		)
		(fp_line
			(start 0.870458 -0.2794)
			(end 0.845058 0.4064)
			(stroke
				(width 0.1524)
				(type default)
			)
			(layer "F.SilkS")
		)
		(fp_line
			(start 0.94488 -0.450088)
			(end -0.854964 -0.450088)
			(stroke
				(width 0.1524)
				(type default)
			)
			(layer "F.SilkS")
		)
		(fp_line
			(start 0.94488 0.450088)
			(end 0.94488 -0.450088)
			(stroke
				(width 0.1524)
				(type default)
			)
			(layer "F.SilkS")
		)
		(fp_line
			(start -0.54991 -0.350012)
			(end -0.54991 0.350012)
			(stroke
				(width 0.1)
				(type default)
			)
			(layer "F.Fab")
		)
		(fp_line
			(start -0.54991 0.350012)
			(end 0.54991 0.350012)
			(stroke
				(width 0.1)
				(type default)
			)
			(layer "F.Fab")
		)
		(fp_line
			(start 0.54991 -0.350012)
			(end -0.54991 -0.350012)
			(stroke
				(width 0.1)
				(type default)
			)
			(layer "F.Fab")
		)
		(fp_line
			(start 0.54991 0.350012)
			(end 0.54991 -0.350012)
			(stroke
				(width 0.1)
				(type default)
			)
			(layer "F.Fab")
		)
		(fp_text user "+"
			(at -0.635 0.407162 180)
			(unlocked yes)
			(layer "F.SilkS")
			(effects
				(font
					(size 1.905 1.4224)
					(thickness 0.1524)
				)
				(justify left)
			)
		)
		(fp_text user "-"
			(at 2.159 0.407162 180)
			(unlocked yes)
			(layer "F.SilkS")
			(effects
				(font
					(size 1.905 1.4224)
					(thickness 0.1524)
				)
				(justify left)
			)
		)
		(fp_text user "+"
			(at -0.808228 0.239014 180)
			(unlocked yes)
			(layer "F.Fab")
			(effects
				(font
					(size 1.905 1.4224)
					(thickness 0.1524)
				)
				(justify left)
			)
		)
		(fp_text user "-"
			(at 2.48539 0.239014 180)
			(unlocked yes)
			(layer "F.Fab")
			(effects
				(font
					(size 1.905 1.4224)
					(thickness 0.1524)
				)
				(justify left)
			)
		)
		(pad "A" smd rect
			(at -0.424942 0)
			(size 0.5588 0.6096)
			(layers "F.Cu" "F.Mask" "F.Paste")
			(net "GND")
		)
		(pad "C" smd rect
			(at 0.424942 0 180)
			(size 0.5588 0.6096)
			(layers "F.Cu" "F.Mask" "F.Paste")
			(net "FAN_2_TACH_IL_D")
		)
	)
	(footprint ""
		(layer "F.Cu")
		(at 14.234922 -14.310868 180)
		(property "Reference" "R5128"
			(at 0 0 180)
			(layer "F.SilkS")
			(hide yes)
			(effects
				(font
					(size 1.27 1.27)
				)
			)
		)
		(property "Value" ""
			(at 0 0 180)
			(layer "F.Fab")
			(effects
				(font
					(size 1.27 1.27)
				)
			)
		)
		(duplicate_pad_numbers_are_jumpers no)
		(fp_line
			(start 0.7874 0.4064)
			(end -0.7874 0.4064)
			(stroke
				(width 0.1524)
				(type default)
			)
			(layer "F.SilkS")
		)
		(fp_line
			(start 0.7874 -0.4064)
			(end 0.7874 0.4064)
			(stroke
				(width 0.1524)
				(type default)
			)
			(layer "F.SilkS")
		)
		(fp_line
			(start -0.7874 0.4064)
			(end -0.7874 -0.4064)
			(stroke
				(width 0.1524)
				(type default)
			)
			(layer "F.SilkS")
		)
		(fp_line
			(start -0.7874 -0.4064)
			(end 0.7874 -0.4064)
			(stroke
				(width 0.1524)
				(type default)
			)
			(layer "F.SilkS")
		)
		(fp_line
			(start 0.67945 0.3048)
			(end 0.120396 0.3048)
			(stroke
				(width 0.1)
				(type default)
			)
			(layer "F.Fab")
		)
		(fp_line
			(start 0.67945 -0.3048)
			(end 0.67945 0.3048)
			(stroke
				(width 0.1)
				(type default)
			)
			(layer "F.Fab")
		)
		(fp_line
			(start 0.12065 -0.2794)
			(end 0.12065 -0.3048)
			(stroke
				(width 0.1)
				(type default)
			)
			(layer "F.Fab")
		)
		(fp_line
			(start 0.12065 -0.3048)
			(end 0.67945 -0.3048)
			(stroke
				(width 0.1)
				(type default)
			)
			(layer "F.Fab")
		)
		(fp_line
			(start 0.120396 0.3048)
			(end 0.120396 0.2794)
			(stroke
				(width 0.1)
				(type default)
			)
			(layer "F.Fab")
		)
		(fp_line
			(start 0.120396 0.2794)
			(end -0.12065 0.2794)
			(stroke
				(width 0.1)
				(type default)
			)
			(layer "F.Fab")
		)
		(fp_line
			(start -0.12065 0.3048)
			(end -0.67945 0.3048)
			(stroke
				(width 0.1)
				(type default)
			)
			(layer "F.Fab")
		)
		(fp_line
			(start -0.12065 0.2794)
			(end -0.12065 0.3048)
			(stroke
				(width 0.1)
				(type default)
			)
			(layer "F.Fab")
		)
		(fp_line
			(start -0.12065 -0.2794)
			(end 0.12065 -0.2794)
			(stroke
				(width 0.1)
				(type default)
			)
			(layer "F.Fab")
		)
		(fp_line
			(start -0.12065 -0.305054)
			(end -0.12065 -0.2794)
			(stroke
				(width 0.1)
				(type default)
			)
			(layer "F.Fab")
		)
		(fp_line
			(start -0.67945 0.3048)
			(end -0.67945 -0.305054)
			(stroke
				(width 0.1)
				(type default)
			)
			(layer "F.Fab")
		)
		(fp_line
			(start -0.67945 -0.305054)
			(end -0.12065 -0.305054)
			(stroke
				(width 0.1)
				(type default)
			)
			(layer "F.Fab")
		)
		(pad "1" smd circle
			(at -0.40005 0 180)
			(size 0 0)
			(layers "F.Cu" "F.Mask" "F.Paste")
			(net "FAN_4_PWM_OL")
		)
		(pad "2" smd circle
			(at 0.40005 0 180)
			(size 0 0)
			(layers "F.Cu" "F.Mask" "F.Paste")
			(net "FAN_4_PWM_OL_R")
		)
	)
	(footprint ""
		(layer "F.Cu")
		(at 18.415 -186.563)
		(property "Reference" "R313"
			(at 0 0 0)
			(layer "F.SilkS")
			(hide yes)
			(effects
				(font
					(size 1.27 1.27)
				)
			)
		)
		(property "Value" ""
			(at 0 0 0)
			(layer "F.Fab")
			(effects
				(font
					(size 1.27 1.27)
				)
			)
		)
		(duplicate_pad_numbers_are_jumpers no)
		(fp_line
			(start -0.7874 -0.4064)
			(end 0.7874 -0.4064)
			(stroke
				(width 0.1524)
				(type default)
			)
			(layer "F.SilkS")
		)
		(fp_line
			(start -0.7874 0.4064)
			(end -0.7874 -0.4064)
			(stroke
				(width 0.1524)
				(type default)
			)
			(layer "F.SilkS")
		)
		(fp_line
			(start 0.7874 -0.4064)
			(end 0.7874 0.4064)
			(stroke
				(width 0.1524)
				(type default)
			)
			(layer "F.SilkS")
		)
		(fp_line
			(start 0.7874 0.4064)
			(end -0.7874 0.4064)
			(stroke
				(width 0.1524)
				(type default)
			)
			(layer "F.SilkS")
		)
		(fp_line
			(start -0.67945 -0.305054)
			(end -0.12065 -0.305054)
			(stroke
				(width 0.1)
				(type default)
			)
			(layer "F.Fab")
		)
		(fp_line
			(start -0.67945 0.3048)
			(end -0.67945 -0.305054)
			(stroke
				(width 0.1)
				(type default)
			)
			(layer "F.Fab")
		)
		(fp_line
			(start -0.12065 -0.305054)
			(end -0.12065 -0.2794)
			(stroke
				(width 0.1)
				(type default)
			)
			(layer "F.Fab")
		)
		(fp_line
			(start -0.12065 -0.2794)
			(end 0.12065 -0.2794)
			(stroke
				(width 0.1)
				(type default)
			)
			(layer "F.Fab")
		)
		(fp_line
			(start -0.12065 0.2794)
			(end -0.12065 0.3048)
			(stroke
				(width 0.1)
				(type default)
			)
			(layer "F.Fab")
		)
		(fp_line
			(start -0.12065 0.3048)
			(end -0.67945 0.3048)
			(stroke
				(width 0.1)
				(type default)
			)
			(layer "F.Fab")
		)
		(fp_line
			(start 0.120396 0.2794)
			(end -0.12065 0.2794)
			(stroke
				(width 0.1)
				(type default)
			)
			(layer "F.Fab")
		)
		(fp_line
			(start 0.120396 0.3048)
			(end 0.120396 0.2794)
			(stroke
				(width 0.1)
				(type default)
			)
			(layer "F.Fab")
		)
		(fp_line
			(start 0.12065 -0.3048)
			(end 0.67945 -0.3048)
			(stroke
				(width 0.1)
				(type default)
			)
			(layer "F.Fab")
		)
		(fp_line
			(start 0.12065 -0.2794)
			(end 0.12065 -0.3048)
			(stroke
				(width 0.1)
				(type default)
			)
			(layer "F.Fab")
		)
		(fp_line
			(start 0.67945 -0.3048)
			(end 0.67945 0.3048)
			(stroke
				(width 0.1)
				(type default)
			)
			(layer "F.Fab")
		)
		(fp_line
			(start 0.67945 0.3048)
			(end 0.120396 0.3048)
			(stroke
				(width 0.1)
				(type default)
			)
			(layer "F.Fab")
		)
		(pad "1" smd circle
			(at -0.40005 0)
			(size 0 0)
			(layers "F.Cu" "F.Mask" "F.Paste")
			(net "SMB_FRU_DAT")
		)
		(pad "2" smd circle
			(at 0.40005 0)
			(size 0 0)
			(layers "F.Cu" "F.Mask" "F.Paste")
			(net "SMB_PDBV_FAN_SDA")
		)
	)
	(footprint ""
		(layer "F.Cu")
		(at 31.623 -143.891 -90)
		(property "Reference" "R4791"
			(at 0 0 270)
			(layer "F.SilkS")
			(hide yes)
			(effects
				(font
					(size 1.27 1.27)
				)
			)
		)
		(property "Value" ""
			(at 0 0 270)
			(layer "F.Fab")
			(effects
				(font
					(size 1.27 1.27)
				)
			)
		)
		(duplicate_pad_numbers_are_jumpers no)
		(fp_line
			(start -0.7874 0.4064)
			(end -0.7874 -0.4064)
			(stroke
				(width 0.1524)
				(type default)
			)
			(layer "F.SilkS")
		)
		(fp_line
			(start 0.7874 0.4064)
			(end -0.7874 0.4064)
			(stroke
				(width 0.1524)
				(type default)
			)
			(layer "F.SilkS")
		)
		(fp_line
			(start -0.7874 -0.4064)
			(end 0.7874 -0.4064)
			(stroke
				(width 0.1524)
				(type default)
			)
			(layer "F.SilkS")
		)
		(fp_line
			(start 0.7874 -0.4064)
			(end 0.7874 0.4064)
			(stroke
				(width 0.1524)
				(type default)
			)
			(layer "F.SilkS")
		)
		(fp_line
			(start -0.67945 0.3048)
			(end -0.67945 -0.305054)
			(stroke
				(width 0.1)
				(type default)
			)
			(layer "F.Fab")
		)
		(fp_line
			(start -0.12065 0.3048)
			(end -0.67945 0.3048)
			(stroke
				(width 0.1)
				(type default)
			)
			(layer "F.Fab")
		)
		(fp_line
			(start 0.120396 0.3048)
			(end 0.120396 0.2794)
			(stroke
				(width 0.1)
				(type default)
			)
			(layer "F.Fab")
		)
		(fp_line
			(start 0.67945 0.3048)
			(end 0.120396 0.3048)
			(stroke
				(width 0.1)
				(type default)
			)
			(layer "F.Fab")
		)
		(fp_line
			(start -0.12065 0.2794)
			(end -0.12065 0.3048)
			(stroke
				(width 0.1)
				(type default)
			)
			(layer "F.Fab")
		)
		(fp_line
			(start 0.120396 0.2794)
			(end -0.12065 0.2794)
			(stroke
				(width 0.1)
				(type default)
			)
			(layer "F.Fab")
		)
		(fp_line
			(start -0.12065 -0.2794)
			(end 0.12065 -0.2794)
			(stroke
				(width 0.1)
				(type default)
			)
			(layer "F.Fab")
		)
		(fp_line
			(start 0.12065 -0.2794)
			(end 0.12065 -0.3048)
			(stroke
				(width 0.1)
				(type default)
			)
			(layer "F.Fab")
		)
		(fp_line
			(start 0.12065 -0.3048)
			(end 0.67945 -0.3048)
			(stroke
				(width 0.1)
				(type default)
			)
			(layer "F.Fab")
		)
		(fp_line
			(start 0.67945 -0.3048)
			(end 0.67945 0.3048)
			(stroke
				(width 0.1)
				(type default)
			)
			(layer "F.Fab")
		)
		(fp_line
			(start -0.67945 -0.305054)
			(end -0.12065 -0.305054)
			(stroke
				(width 0.1)
				(type default)
			)
			(layer "F.Fab")
		)
		(fp_line
			(start -0.12065 -0.305054)
			(end -0.12065 -0.2794)
			(stroke
				(width 0.1)
				(type default)
			)
			(layer "F.Fab")
		)
		(pad "1" smd circle
			(at -0.40005 0 270)
			(size 0 0)
			(layers "F.Cu" "F.Mask" "F.Paste")
			(net "SMB_FAN2_R_SCL")
		)
		(pad "2" smd circle
			(at 0.40005 0 270)
			(size 0 0)
			(layers "F.Cu" "F.Mask" "F.Paste")
			(net "SMB_FAN2_SCL")
		)
	)
	(footprint ""
		(layer "F.Cu")
		(at 14.859 -132.334)
		(property "Reference" "R5617"
			(at 0 0 0)
			(layer "F.SilkS")
			(hide yes)
			(effects
				(font
					(size 1.27 1.27)
				)
			)
		)
		(property "Value" ""
			(at 0 0 0)
			(layer "F.Fab")
			(effects
				(font
					(size 1.27 1.27)
				)
			)
		)
		(duplicate_pad_numbers_are_jumpers no)
		(fp_line
			(start -0.7874 -0.4064)
			(end 0.7874 -0.4064)
			(stroke
				(width 0.1524)
				(type default)
			)
			(layer "F.SilkS")
		)
		(fp_line
			(start -0.7874 0.4064)
			(end -0.7874 -0.4064)
			(stroke
				(width 0.1524)
				(type default)
			)
			(layer "F.SilkS")
		)
		(fp_line
			(start 0.7874 -0.4064)
			(end 0.7874 0.4064)
			(stroke
				(width 0.1524)
				(type default)
			)
			(layer "F.SilkS")
		)
		(fp_line
			(start 0.7874 0.4064)
			(end -0.7874 0.4064)
			(stroke
				(width 0.1524)
				(type default)
			)
			(layer "F.SilkS")
		)
		(fp_line
			(start -0.67945 -0.305054)
			(end -0.12065 -0.305054)
			(stroke
				(width 0.1)
				(type default)
			)
			(layer "F.Fab")
		)
		(fp_line
			(start -0.67945 0.3048)
			(end -0.67945 -0.305054)
			(stroke
				(width 0.1)
				(type default)
			)
			(layer "F.Fab")
		)
		(fp_line
			(start -0.12065 -0.305054)
			(end -0.12065 -0.2794)
			(stroke
				(width 0.1)
				(type default)
			)
			(layer "F.Fab")
		)
		(fp_line
			(start -0.12065 -0.2794)
			(end 0.12065 -0.2794)
			(stroke
				(width 0.1)
				(type default)
			)
			(layer "F.Fab")
		)
		(fp_line
			(start -0.12065 0.2794)
			(end -0.12065 0.3048)
			(stroke
				(width 0.1)
				(type default)
			)
			(layer "F.Fab")
		)
		(fp_line
			(start -0.12065 0.3048)
			(end -0.67945 0.3048)
			(stroke
				(width 0.1)
				(type default)
			)
			(layer "F.Fab")
		)
		(fp_line
			(start 0.120396 0.2794)
			(end -0.12065 0.2794)
			(stroke
				(width 0.1)
				(type default)
			)
			(layer "F.Fab")
		)
		(fp_line
			(start 0.120396 0.3048)
			(end 0.120396 0.2794)
			(stroke
				(width 0.1)
				(type default)
			)
			(layer "F.Fab")
		)
		(fp_line
			(start 0.12065 -0.3048)
			(end 0.67945 -0.3048)
			(stroke
				(width 0.1)
				(type default)
			)
			(layer "F.Fab")
		)
		(fp_line
			(start 0.12065 -0.2794)
			(end 0.12065 -0.3048)
			(stroke
				(width 0.1)
				(type default)
			)
			(layer "F.Fab")
		)
		(fp_line
			(start 0.67945 -0.3048)
			(end 0.67945 0.3048)
			(stroke
				(width 0.1)
				(type default)
			)
			(layer "F.Fab")
		)
		(fp_line
			(start 0.67945 0.3048)
			(end 0.120396 0.3048)
			(stroke
				(width 0.1)
				(type default)
			)
			(layer "F.Fab")
		)
		(pad "1" smd rect
			(at -0.40005 0 180)
			(size 0.4572 0.508)
			(layers "F.Cu" "F.Mask" "F.Paste")
			(net "FAN_7_TACH_IL")
		)
		(pad "2" smd rect
			(at 0.40005 0 180)
			(size 0.4572 0.508)
			(layers "F.Cu" "F.Mask" "F.Paste")
			(net "FAN_7_TACH_IL_R1")
		)
	)
)
